(kicad_pcb
	(version 20260206)
	(generator "pcbnew")
	(generator_version "10.0")
	(general
		(thickness 1.6)
		(legacy_teardrops no)
	)
	(paper "A4")
	(title_block
		(title "Wiwynn_Tioga_Pass_MB.brd")
		(comment 1 "Tioga Pass / footprints 1274-1279 of 4770")
	)
	(layers
		(0 "F.Cu" signal "TOP")
		(4 "In1.Cu" signal "L2GND")
		(6 "In2.Cu" signal "L3")
		(8 "In3.Cu" signal "L4GND")
		(10 "In4.Cu" signal "L5")
		(12 "In5.Cu" signal "L6GND")
		(14 "In6.Cu" signal "L7VCC")
		(16 "In7.Cu" signal "L8VCC")
		(18 "In8.Cu" signal "L9GND")
		(20 "In9.Cu" signal "L10")
		(22 "In10.Cu" signal "L11GND")
		(24 "In11.Cu" signal "L12")
		(26 "In12.Cu" signal "L13GND")
		(2 "B.Cu" signal "BOTTOM")
		(9 "F.Adhes" user "F.Adhesive")
		(11 "B.Adhes" user "B.Adhesive")
		(13 "F.Paste" user "Package Geometry/Pastemask Top")
		(15 "B.Paste" user "Package Geometry/Pastemask Bottom")
		(5 "F.SilkS" user "Ref Des/Silkscreen Top")
		(7 "B.SilkS" user "Ref Des/Silkscreen Bottom")
		(1 "F.Mask" user "Board Geometry/Soldermask Top")
		(3 "B.Mask" user "Board Geometry/Soldermask Bottom")
		(17 "Dwgs.User" user "User.Drawings")
		(19 "Cmts.User" user "User.Comments")
		(21 "Eco1.User" user "User.Eco1")
		(23 "Eco2.User" user "User.Eco2")
		(25 "Edge.Cuts" user "Board Geometry/Outline")
		(27 "Margin" user)
		(31 "F.CrtYd" user "Package Geometry/Place Bound Top")
		(29 "B.CrtYd" user "Package Geometry/Place Bound Bottom")
		(35 "F.Fab" user "Ref Des/Assembly Top")
		(33 "B.Fab" user "Ref Des/Assembly Bottom")
	)
	(footprint ""
		(layer "F.Cu")
		(at 403.112986 -84.582 -90)
		(property "Reference" "U2P1"
			(at 2.1463 3.50901 90)
			(unlocked yes)
			(layer "F.SilkS")
			(effects
				(font
					(size 0.7874 0.5842)
					(thickness 0.1524)
				)
				(justify left)
			)
		)
		(property "Value" ""
			(at 0 0 270)
			(layer "F.Fab")
			(effects
				(font
					(size 1.27 1.27)
				)
			)
		)
		(duplicate_pad_numbers_are_jumpers no)
		(fp_circle
			(center -0.4699 -0.8382)
			(end -0.4699 -0.9652)
			(stroke
				(width 0.254)
				(type default)
			)
			(fill no)
			(layer "F.SilkS")
		)
		(fp_poly
			(pts
				(xy 0.21463 -0.450088) (xy 1.56337 -0.450088) (xy 1.56337 1.75006) (xy 0.21463 1.75006)
			)
			(stroke
				(width 0)
				(type default)
			)
			(fill no)
			(layer "F.CrtYd")
		)
		(fp_line
			(start 0.21463 1.75006)
			(end 0.21463 -0.450088)
			(stroke
				(width 0.1)
				(type default)
			)
			(layer "F.Fab")
		)
		(fp_line
			(start 1.56337 1.75006)
			(end 0.21463 1.75006)
			(stroke
				(width 0.1)
				(type default)
			)
			(layer "F.Fab")
		)
		(fp_line
			(start 0.21463 -0.450088)
			(end 1.56337 -0.450088)
			(stroke
				(width 0.1)
				(type default)
			)
			(layer "F.Fab")
		)
		(fp_line
			(start 1.56337 -0.450088)
			(end 1.56337 1.75006)
			(stroke
				(width 0.1)
				(type default)
			)
			(layer "F.Fab")
		)
		(fp_circle
			(center -0.4699 -0.8382)
			(end -0.4699 -0.9652)
			(stroke
				(width 0.254)
				(type default)
			)
			(fill no)
			(layer "F.Fab")
		)
		(pad "1" smd rect
			(at 0 0 270)
			(size 1.016 0.381)
			(layers "F.Cu" "F.Mask" "F.Paste")
			(net "Net_6470")
		)
		(pad "2" smd rect
			(at 0 0.649986 270)
			(size 1.016 0.381)
			(layers "F.Cu" "F.Mask" "F.Paste")
			(net "FM_M2_SSD_PEDET")
		)
		(pad "3" smd rect
			(at 0 1.299972 270)
			(size 1.016 0.381)
			(layers "F.Cu" "F.Mask" "F.Paste")
			(net "GND")
		)
		(pad "4" smd rect
			(at 1.778 1.299972 270)
			(size 1.016 0.381)
			(layers "F.Cu" "F.Mask" "F.Paste")
			(net "FM_M2_DET_LVC3")
		)
		(pad "5" smd rect
			(at 1.778 0 270)
			(size 1.016 0.381)
			(layers "F.Cu" "F.Mask" "F.Paste")
			(net "P3V3_STBY")
		)
	)
	(footprint ""
		(layer "F.Cu")
		(at 426.5295 -126.5047 -90)
		(property "Reference" "R8B11"
			(at 0 0 270)
			(layer "F.SilkS")
			(hide yes)
			(effects
				(font
					(size 1.27 1.27)
				)
			)
		)
		(property "Value" ""
			(at 0 0 270)
			(layer "F.Fab")
			(effects
				(font
					(size 1.27 1.27)
				)
			)
		)
		(duplicate_pad_numbers_are_jumpers no)
		(fp_poly
			(pts
				(xy -0.2794 -0.1016) (xy 0.2794 -0.1016) (xy 0.2794 0.9906) (xy -0.2794 0.9906)
			)
			(stroke
				(width 0)
				(type default)
			)
			(fill no)
			(layer "F.CrtYd")
		)
		(fp_line
			(start -0.2794 0.9906)
			(end 0.2794 0.9906)
			(stroke
				(width 0.1)
				(type default)
			)
			(layer "F.Fab")
		)
		(fp_line
			(start 0.2794 0.9906)
			(end 0.2794 -0.1016)
			(stroke
				(width 0.1)
				(type default)
			)
			(layer "F.Fab")
		)
		(fp_line
			(start -0.2794 -0.1016)
			(end -0.2794 0.9906)
			(stroke
				(width 0.1)
				(type default)
			)
			(layer "F.Fab")
		)
		(fp_line
			(start 0.2794 -0.1016)
			(end -0.2794 -0.1016)
			(stroke
				(width 0.1)
				(type default)
			)
			(layer "F.Fab")
		)
		(pad "1" smd rect
			(at 0 0 270)
			(size 0.508 0.508)
			(layers "F.Cu" "F.Mask" "F.Paste")
			(net "PVPP_ABC")
		)
		(pad "2" smd rect
			(at 0 0.889 270)
			(size 0.508 0.508)
			(layers "F.Cu" "F.Mask" "F.Paste")
			(net "SMB_HFI1_CPU0_LVC2_SCL")
		)
		(zone
			(layer "F.Cu")
			(hatch none 0.5)
			(connect_pads
				(clearance 0)
			)
			(min_thickness 0.25)
			(keepout
				(tracks not_allowed)
				(vias allowed)
				(pads allowed)
				(copperpour not_allowed)
				(footprints allowed)
			)
			(placement
				(enabled no)
				(sheetname "")
			)
			(fill
				(thermal_gap 0.5)
				(thermal_bridge_width 0.5)
				(island_removal_mode 0)
			)
			(polygon
				(pts
					(xy 425.8945 -126.7587) (xy 425.8945 -126.2507) (xy 426.2755 -126.2507) (xy 426.2755 -126.7587)
				)
			)
		)
		(zone
			(layer "F.Cu")
			(hatch none 0.5)
			(connect_pads
				(clearance 0)
			)
			(min_thickness 0.25)
			(keepout
				(tracks allowed)
				(vias not_allowed)
				(pads allowed)
				(copperpour not_allowed)
				(footprints allowed)
			)
			(placement
				(enabled no)
				(sheetname "")
			)
			(fill
				(thermal_gap 0.5)
				(thermal_bridge_width 0.5)
				(island_removal_mode 0)
			)
			(polygon
				(pts
					(xy 426.2755 -126.7587) (xy 426.2755 -126.2507) (xy 425.8945 -126.2507) (xy 425.8945 -126.7587)
				)
			)
		)
	)
	(footprint ""
		(layer "F.Cu")
		(at 32.416496 -69.223382 -90)
		(property "Reference" "C1D17"
			(at 0 0 270)
			(layer "F.SilkS")
			(hide yes)
			(effects
				(font
					(size 1.27 1.27)
				)
			)
		)
		(property "Value" ""
			(at 0 0 270)
			(layer "F.Fab")
			(effects
				(font
					(size 1.27 1.27)
				)
			)
		)
		(duplicate_pad_numbers_are_jumpers no)
		(fp_rect
			(start 0.3048 0.9906)
			(end -0.3048 -0.1016)
			(stroke
				(width 0)
				(type default)
			)
			(fill no)
			(layer "F.CrtYd")
		)
		(fp_line
			(start -0.3048 0.9906)
			(end 0.3048 0.9906)
			(stroke
				(width 0.1)
				(type default)
			)
			(layer "F.Fab")
		)
		(fp_line
			(start 0.3048 0.9906)
			(end 0.3048 -0.1016)
			(stroke
				(width 0.1)
				(type default)
			)
			(layer "F.Fab")
		)
		(fp_line
			(start -0.3048 -0.1016)
			(end -0.3048 0.9906)
			(stroke
				(width 0.1)
				(type default)
			)
			(layer "F.Fab")
		)
		(fp_line
			(start 0.3048 -0.1016)
			(end -0.3048 -0.1016)
			(stroke
				(width 0.1)
				(type default)
			)
			(layer "F.Fab")
		)
		(pad "1" smd rect
			(at 0 0 270)
			(size 0.508 0.508)
			(layers "F.Cu" "F.Mask" "F.Paste")
			(net "VR_PVCCIN_CPU1_PH3_VCIN")
		)
		(pad "2" smd rect
			(at 0 0.889 270)
			(size 0.508 0.508)
			(layers "F.Cu" "F.Mask" "F.Paste")
			(net "GND")
		)
		(zone
			(layer "F.Cu")
			(hatch none 0.5)
			(connect_pads
				(clearance 0)
			)
			(min_thickness 0.25)
			(keepout
				(tracks allowed)
				(vias not_allowed)
				(pads allowed)
				(copperpour not_allowed)
				(footprints allowed)
			)
			(placement
				(enabled no)
				(sheetname "")
			)
			(fill
				(thermal_gap 0.5)
				(thermal_bridge_width 0.5)
				(island_removal_mode 0)
			)
			(polygon
				(pts
					(xy 31.781496 -68.969382) (xy 32.162496 -68.969382) (xy 32.162496 -69.477382) (xy 31.781496 -69.477382)
				)
			)
		)
		(zone
			(layer "F.Cu")
			(hatch none 0.5)
			(connect_pads
				(clearance 0)
			)
			(min_thickness 0.25)
			(keepout
				(tracks not_allowed)
				(vias allowed)
				(pads allowed)
				(copperpour not_allowed)
				(footprints allowed)
			)
			(placement
				(enabled no)
				(sheetname "")
			)
			(fill
				(thermal_gap 0.5)
				(thermal_bridge_width 0.5)
				(island_removal_mode 0)
			)
			(polygon
				(pts
					(xy 31.781496 -68.969382) (xy 32.162496 -68.969382) (xy 32.162496 -69.477382) (xy 31.781496 -69.477382)
				)
			)
		)
	)
	(footprint ""
		(layer "F.Cu")
		(at 21.222462 -57.0992 180)
		(property "Reference" "EU1E3"
			(at 2.299462 -1.49987 0)
			(unlocked yes)
			(layer "F.SilkS")
			(effects
				(font
					(size 0.7874 0.5842)
					(thickness 0.1524)
				)
			)
		)
		(property "Value" ""
			(at 0 0 180)
			(layer "F.Fab")
			(effects
				(font
					(size 1.27 1.27)
				)
			)
		)
		(duplicate_pad_numbers_are_jumpers no)
		(fp_line
			(start 4.8006 4.5593)
			(end 4.8006 4.445254)
			(stroke
				(width 0.1524)
				(type default)
			)
			(layer "F.SilkS")
		)
		(fp_line
			(start 4.8006 -0.7493)
			(end 4.8006 -0.635254)
			(stroke
				(width 0.1524)
				(type default)
			)
			(layer "F.SilkS")
		)
		(fp_line
			(start 0.4064 4.5593)
			(end 4.8006 4.5593)
			(stroke
				(width 0.1524)
				(type default)
			)
			(layer "F.SilkS")
		)
		(fp_line
			(start 0.4064 4.445254)
			(end 0.4064 4.5593)
			(stroke
				(width 0.1524)
				(type default)
			)
			(layer "F.SilkS")
		)
		(fp_line
			(start 0.4064 -0.635254)
			(end 0.4064 -0.7493)
			(stroke
				(width 0.1524)
				(type default)
			)
			(layer "F.SilkS")
		)
		(fp_line
			(start 0.4064 -0.7493)
			(end 4.8006 -0.7493)
			(stroke
				(width 0.1524)
				(type default)
			)
			(layer "F.SilkS")
		)
		(fp_circle
			(center -1.279906 -0.230378)
			(end -1.406906 -0.230378)
			(stroke
				(width 0.254)
				(type default)
			)
			(fill no)
			(layer "F.SilkS")
		)
		(fp_rect
			(start 4.8006 -0.7493)
			(end 0.4064 4.5593)
			(stroke
				(width 0)
				(type default)
			)
			(fill no)
			(layer "F.CrtYd")
		)
		(fp_line
			(start 4.8006 4.5593)
			(end 0.4064 4.5593)
			(stroke
				(width 0.1)
				(type default)
			)
			(layer "F.Fab")
		)
		(fp_line
			(start 4.8006 -0.7493)
			(end 4.8006 4.5593)
			(stroke
				(width 0.1)
				(type default)
			)
			(layer "F.Fab")
		)
		(fp_line
			(start 0.4064 4.5593)
			(end 0.4064 -0.7493)
			(stroke
				(width 0.1)
				(type default)
			)
			(layer "F.Fab")
		)
		(fp_line
			(start 0.4064 -0.7493)
			(end 4.8006 -0.7493)
			(stroke
				(width 0.1)
				(type default)
			)
			(layer "F.Fab")
		)
		(fp_circle
			(center -1.076706 -0.704342)
			(end -1.203706 -0.704342)
			(stroke
				(width 0.635)
				(type default)
			)
			(fill no)
			(layer "F.Fab")
		)
		(pad "1" smd rect
			(at 0 0 180)
			(size 1.651 0.508)
			(layers "F.Cu" "F.Mask" "F.Paste")
			(net "P12V_STBY")
		)
		(pad "2" smd rect
			(at 0 1.27 180)
			(size 1.651 0.508)
			(layers "F.Cu" "F.Mask" "F.Paste")
			(net "P12V_STBY")
		)
		(pad "3" smd rect
			(at 0 2.54 180)
			(size 1.651 0.508)
			(layers "F.Cu" "F.Mask" "F.Paste")
			(net "P12V_STBY")
		)
		(pad "4" smd rect
			(at 0 3.81 180)
			(size 1.651 0.508)
			(layers "F.Cu" "F.Mask" "F.Paste")
			(net "A_HSC_GATE1_R")
		)
		(pad "5" smd custom
			(at 3.937 1.905 180)
			(size 1.04775 1.04775)
			(layers "F.Cu" "F.Mask" "F.Paste")
			(net "P12V_MB0_SW")
			(options
				(clearance outline)
				(anchor circle)
			)
			(primitives
				(gr_poly
					(pts
						(xy -2.0955 -1.651) (xy -2.0955 1.651) (xy 0.4445 1.651) (xy 0.4445 2.2098) (xy 2.0955 2.2098)
						(xy 2.0955 -2.2098) (xy 0.4445 -2.2098) (xy 0.4445 -1.651)
					)
					(width 0)
					(fill yes)
				)
			)
		)
	)
	(footprint ""
		(layer "F.Cu")
		(at 416.402012 -52.738782)
		(property "Reference" "Q1W4"
			(at 0 -0.81788 0)
			(unlocked yes)
			(layer "F.SilkS")
			(effects
				(font
					(size 0.4064 0.254)
					(thickness 0.1524)
				)
				(justify left)
			)
		)
		(property "Value" ""
			(at 0 0 0)
			(layer "F.Fab")
			(effects
				(font
					(size 1.27 1.27)
				)
			)
		)
		(duplicate_pad_numbers_are_jumpers no)
		(fp_circle
			(center -0.848614 -0.6477)
			(end -0.721614 -0.6477)
			(stroke
				(width 0.254)
				(type default)
			)
			(fill no)
			(layer "F.SilkS")
		)
		(fp_poly
			(pts
				(xy 0.21463 -0.450088) (xy 1.56337 -0.450088) (xy 1.56337 1.75006) (xy 0.21463 1.75006)
			)
			(stroke
				(width 0)
				(type default)
			)
			(fill no)
			(layer "F.CrtYd")
		)
		(fp_line
			(start 0.21463 -0.450088)
			(end 1.56337 -0.450088)
			(stroke
				(width 0.1)
				(type default)
			)
			(layer "F.Fab")
		)
		(fp_line
			(start 0.21463 1.75006)
			(end 0.21463 -0.450088)
			(stroke
				(width 0.1)
				(type default)
			)
			(layer "F.Fab")
		)
		(fp_line
			(start 1.56337 -0.450088)
			(end 1.56337 1.75006)
			(stroke
				(width 0.1)
				(type default)
			)
			(layer "F.Fab")
		)
		(fp_line
			(start 1.56337 1.75006)
			(end 0.21463 1.75006)
			(stroke
				(width 0.1)
				(type default)
			)
			(layer "F.Fab")
		)
		(fp_circle
			(center -0.848614 -0.6477)
			(end -0.721614 -0.6477)
			(stroke
				(width 0.254)
				(type default)
			)
			(fill no)
			(layer "F.Fab")
		)
		(pad "1" smd rect
			(at 0 0)
			(size 1.016 0.381)
			(layers "F.Cu" "F.Mask" "F.Paste")
			(net "GND")
		)
		(pad "2" smd rect
			(at 0 0.649986)
			(size 1.016 0.381)
			(layers "F.Cu" "F.Mask" "F.Paste")
			(net "FM_OCP_MEZZC_PRES_N")
		)
		(pad "3" smd rect
			(at 0 1.299972)
			(size 1.016 0.381)
			(layers "F.Cu" "F.Mask" "F.Paste")
			(net "FM_OCP_MEZZC_PRES_1V05_PCH_N")
		)
		(pad "4" smd rect
			(at 1.778 1.299972)
			(size 1.016 0.381)
			(layers "F.Cu" "F.Mask" "F.Paste")
			(net "GND")
		)
		(pad "5" smd rect
			(at 1.778 0.649986)
			(size 1.016 0.381)
			(layers "F.Cu" "F.Mask" "F.Paste")
			(net "FM_OCP_MEZZC_PRES_LVT3_BMC")
		)
		(pad "6" smd rect
			(at 1.778 0)
			(size 1.016 0.381)
			(layers "F.Cu" "F.Mask" "F.Paste")
			(net "FM_OCP_MEZZC_PRES_LVT3_BMC")
		)
	)
	(footprint ""
		(layer "F.Cu")
		(at 236.715808 -164.90188 -90)
		(property "Reference" "T1D21"
			(at 0 0 270)
			(layer "F.SilkS")
			(hide yes)
			(effects
				(font
					(size 1.27 1.27)
				)
			)
		)
		(property "Value" "*"
			(at -3.4036 -4.46405 270)
			(unlocked yes)
			(layer "F.Fab")
			(hide yes)
			(effects
				(font
					(size 0.889 0.889)
					(thickness 0.1524)
				)
			)
		)
		(property "Device Type" "TEST-PAD-12P-1-GP-U_DISCRET-GBA"
			(at -3.4036 -5.98805 270)
			(unlocked yes)
			(layer "F.Fab")
			(hide yes)
			(effects
				(font
					(size 0.889 0.889)
					(thickness 0.1524)
				)
			)
		)
		(duplicate_pad_numbers_are_jumpers no)
		(fp_line
			(start -2.3876 3.4798)
			(end -2.3876 -4.826)
			(stroke
				(width 0.1524)
				(type default)
			)
			(layer "F.SilkS")
		)
		(fp_line
			(start 2.3622 3.4798)
			(end -2.3876 3.4798)
			(stroke
				(width 0.1524)
				(type default)
			)
			(layer "F.SilkS")
		)
		(fp_line
			(start -2.3876 -4.826)
			(end 2.3622 -4.826)
			(stroke
				(width 0.1524)
				(type default)
			)
			(layer "F.SilkS")
		)
		(fp_line
			(start 2.3622 -4.826)
			(end 2.3622 3.4798)
			(stroke
				(width 0.1524)
				(type default)
			)
			(layer "F.SilkS")
		)
		(fp_rect
			(start -2.6416 3.7338)
			(end 2.6162 -5.08)
			(stroke
				(width 0)
				(type default)
			)
			(fill no)
			(layer "F.CrtYd")
		)
		(fp_rect
			(start -2.6416 3.7338)
			(end 2.6162 -5.08)
			(stroke
				(width 0)
				(type default)
			)
			(fill no)
			(layer "F.Fab")
		)
		(pad "1" smd circle
			(at 0.496824 -1.301496 270)
			(size 0.6604 0.6604)
			(layers "F.Cu" "F.Mask" "F.Paste")
			(net "L12_85OHM_10INCH_DP")
		)
		(pad "2" smd circle
			(at -0.503936 -1.301496 270)
			(size 0.6604 0.6604)
			(layers "F.Cu" "F.Mask" "F.Paste")
			(net "L12_85OHM_10INCH_DN")
		)
		(pad "3" smd custom
			(at -0.00889 0.370078 270)
			(size 0.74295 0.74295)
			(layers "F.Cu" "F.Mask" "F.Paste")
			(net "GND")
			(options
				(clearance outline)
				(anchor circle)
			)
			(primitives
				(gr_poly
					(pts
						(xy -2.1209 1.4859) (xy 2.1209 1.4859) (xy 2.1209 -1.4859) (xy 1.08585 -1.4859) (xy 1.08585 -0.4699)
						(xy -1.08585 -0.4699) (xy -1.08585 -1.4859) (xy -2.1209 -1.4859)
					)
					(width 0)
					(fill yes)
				)
			)
		)
		(pad "4" thru_hole circle
			(at 1.266444 -3.851656 270)
			(size 1.4478 1.4478)
			(drill 1.0414)
			(layers "*.Cu" "*.Mask")
			(remove_unused_layers no)
			(net "GND")
			(clearance 0.1524)
			(thermal_gap 0.1524)
		)
		(pad "5" thru_hole circle
			(at -1.273556 -3.851656 270)
			(size 1.4478 1.4478)
			(drill 1.0414)
			(layers "*.Cu" "*.Mask")
			(remove_unused_layers no)
			(net "GND")
			(clearance 0.1524)
			(thermal_gap 0.1524)
		)
		(pad "6" thru_hole circle
			(at 1.266444 2.498344 270)
			(size 1.4478 1.4478)
			(drill 1.0414)
			(layers "*.Cu" "*.Mask")
			(remove_unused_layers no)
			(net "GND")
			(clearance 0.1524)
			(thermal_gap 0.1524)
		)
		(pad "7" thru_hole circle
			(at -1.273556 2.498344 270)
			(size 1.4478 1.4478)
			(drill 1.0414)
			(layers "*.Cu" "*.Mask")
			(remove_unused_layers no)
			(net "GND")
			(clearance 0.1524)
			(thermal_gap 0.1524)
		)
		(pad "8" thru_hole circle
			(at 1.27 -0.4572 270)
			(size 0.7112 0.7112)
			(drill 0.4064)
			(layers "*.Cu" "*.Mask")
			(remove_unused_layers no)
			(net "GND")
			(clearance 0.1016)
			(thermal_gap 0.1016)
		)
		(pad "9" thru_hole circle
			(at 1.27 0.762 270)
			(size 0.7112 0.7112)
			(drill 0.4064)
			(layers "*.Cu" "*.Mask")
			(remove_unused_layers no)
			(net "GND")
			(clearance 0.1016)
			(thermal_gap 0.1016)
		)
		(pad "10" thru_hole circle
			(at -0.0254 0.762 270)
			(size 0.7112 0.7112)
			(drill 0.4064)
			(layers "*.Cu" "*.Mask")
			(remove_unused_layers no)
			(net "GND")
			(clearance 0.1016)
			(thermal_gap 0.1016)
		)
		(pad "11" thru_hole circle
			(at -1.27 0.762 270)
			(size 0.7112 0.7112)
			(drill 0.4064)
			(layers "*.Cu" "*.Mask")
			(remove_unused_layers no)
			(net "GND")
			(clearance 0.1016)
			(thermal_gap 0.1016)
		)
		(pad "12" thru_hole circle
			(at -1.27 -0.4572 270)
			(size 0.7112 0.7112)
			(drill 0.4064)
			(layers "*.Cu" "*.Mask")
			(remove_unused_layers no)
			(net "GND")
			(clearance 0.1016)
			(thermal_gap 0.1016)
		)
	)
)
